FILE_TYPE = CONNECTIVITY;
{Allegro Design Entry HDL 17.4-2019 S026 (4007227) 1/17/2022}
"PAGE_NUMBER" = 41;
0"NC";
1"M_E_CPU1_SA_DQ<31:0>";
2"M_E_CPU1_SB_DQ<31:0>";
3"M_E_CPU1_SA_CB<7:0>";
4"M_E_CPU1_SB_CB<7:0>";
5"M_E_CPU1_SA_DQS_DN<9:0>";
6"M_E_CPU1_SA_DQS_DP<9:0>";
7"M_E_CPU1_SB_DQS_DN<9:0>";
8"M_E_CPU1_SB_DQS_DP<9:0>";
9"M_E_CPU1_SA_CA<6:0>";
10"M_E_CPU1_SB_CA<6:0>";
11"M_E_CPU1_ALERT_N";
12"M_E_CPU1_ALERT_R_N";
13"TP_M_E_CPU1_SA_TEST39E";
14"M_E_CPU1_CLK_DP<0>";
15"M_E_CPU1_CLK_DN<0>";
16"M_E_CPU1_SA_CS_N<0>";
17"M_E_CPU1_SA_RSP<0>";
18"M_E_CPU1_SA_CS_N<1>";
19"M_E_CPU1_SA_PAR";
20"M_E_CPU1_SB_CS_N<1>";
21"M_E_CPU1_SB_CS_N<0>";
22"M_E_CPU1_SB_RSP<0>";
23"M_E_CPU1_SB_PAR";
24"M_E_CPU1_RESET_N";
25"M_E_CPU1_SB_DQS_DP<9>";
26"M_E_CPU1_SB_CA<6>";
27"M_E_CPU1_SA_CA<6>";
28"M_E_CPU1_SB_CA<5>";
29"M_E_CPU1_SA_CA<5>";
30"M_E_CPU1_SB_CA<4>";
31"M_E_CPU1_SA_CA<4>";
32"M_E_CPU1_SB_CA<3>";
33"M_E_CPU1_SA_CA<3>";
34"M_E_CPU1_SB_CA<2>";
35"M_E_CPU1_SA_CA<2>";
36"M_E_CPU1_SB_CA<1>";
37"M_E_CPU1_SB_DQS_DN<9>";
38"M_E_CPU1_SA_CA<1>";
39"M_E_CPU1_SB_CA<0>";
40"M_E_CPU1_SB_DQS_DN<8>";
41"M_E_CPU1_SA_CA<0>";
42"M_E_CPU1_SB_DQS_DN<1>";
43"M_E_CPU1_SB_DQS_DN<0>";
44"M_E_CPU1_SB_DQS_DP<8>";
45"M_E_CPU1_SB_DQS_DP<7>";
46"M_E_CPU1_SB_DQS_DP<6>";
47"M_E_CPU1_SB_DQS_DP<5>";
48"M_E_CPU1_SB_DQS_DP<4>";
49"M_E_CPU1_SA_DQS_DP<9>";
50"M_E_CPU1_SB_DQS_DP<3>";
51"M_E_CPU1_SB_DQS_DN<7>";
52"M_E_CPU1_SB_DQS_DP<2>";
53"M_E_CPU1_SB_DQS_DN<6>";
54"M_E_CPU1_SB_DQS_DP<1>";
55"M_E_CPU1_SB_DQS_DN<5>";
56"M_E_CPU1_SB_DQS_DP<0>";
57"M_E_CPU1_SB_DQS_DN<4>";
58"M_E_CPU1_SA_DQS_DN<9>";
59"M_E_CPU1_SB_DQS_DN<3>";
60"M_E_CPU1_SB_DQS_DN<2>";
61"M_E_CPU1_SA_DQS_DP<3>";
62"M_E_CPU1_SA_DQS_DN<7>";
63"M_E_CPU1_SA_DQS_DP<2>";
64"M_E_CPU1_SA_DQS_DN<6>";
65"M_E_CPU1_SA_DQS_DP<1>";
66"M_E_CPU1_SA_DQS_DN<5>";
67"M_E_CPU1_SA_DQS_DP<0>";
68"M_E_CPU1_SA_DQS_DN<4>";
69"M_E_CPU1_SA_DQS_DN<3>";
70"M_E_CPU1_SA_DQS_DN<2>";
71"M_E_CPU1_SA_DQS_DN<1>";
72"M_E_CPU1_SA_DQS_DN<0>";
73"M_E_CPU1_SA_DQS_DP<8>";
74"M_E_CPU1_SA_DQS_DP<7>";
75"M_E_CPU1_SA_DQS_DP<6>";
76"M_E_CPU1_SA_DQS_DP<5>";
77"M_E_CPU1_SA_DQS_DP<4>";
78"M_E_CPU1_SA_DQS_DN<8>";
79"M_E_CPU1_SB_CB<5>";
80"M_E_CPU1_SB_CB<4>";
81"M_E_CPU1_SB_CB<3>";
82"M_E_CPU1_SB_CB<2>";
83"M_E_CPU1_SA_CB<7>";
84"M_E_CPU1_SB_CB<1>";
85"M_E_CPU1_SB_CB<0>";
86"M_E_CPU1_SB_CB<7>";
87"M_E_CPU1_SB_CB<6>";
88"M_E_CPU1_SB_DQ<25>";
89"M_E_CPU1_SB_DQ<24>";
90"M_E_CPU1_SB_DQ<23>";
91"M_E_CPU1_SB_DQ<22>";
92"M_E_CPU1_SB_DQ<21>";
93"M_E_CPU1_SA_CB<6>";
94"M_E_CPU1_SB_DQ<31>";
95"M_E_CPU1_SA_CB<5>";
96"M_E_CPU1_SB_DQ<30>";
97"M_E_CPU1_SA_CB<4>";
98"M_E_CPU1_SA_CB<3>";
99"M_E_CPU1_SA_CB<2>";
100"M_E_CPU1_SA_CB<1>";
101"M_E_CPU1_SA_CB<0>";
102"M_E_CPU1_SB_DQ<29>";
103"M_E_CPU1_SB_DQ<28>";
104"M_E_CPU1_SB_DQ<27>";
105"M_E_CPU1_SB_DQ<26>";
106"M_E_CPU1_SB_DQ<14>";
107"M_E_CPU1_SB_DQ<13>";
108"M_E_CPU1_SB_DQ<12>";
109"M_E_CPU1_SB_DQ<9>";
110"M_E_CPU1_SB_DQ<11>";
111"M_E_CPU1_SB_DQ<8>";
112"M_E_CPU1_SB_DQ<10>";
113"M_E_CPU1_SB_DQ<7>";
114"M_E_CPU1_SB_DQ<20>";
115"M_E_CPU1_SB_DQ<6>";
116"M_E_CPU1_SB_DQ<5>";
117"M_E_CPU1_SB_DQ<4>";
118"M_E_CPU1_SB_DQ<3>";
119"M_E_CPU1_SB_DQ<2>";
120"M_E_CPU1_SB_DQ<19>";
121"M_E_CPU1_SB_DQ<18>";
122"M_E_CPU1_SB_DQ<17>";
123"M_E_CPU1_SB_DQ<16>";
124"M_E_CPU1_SB_DQ<15>";
125"M_E_CPU1_SA_DQ<19>";
126"M_E_CPU1_SA_DQ<18>";
127"M_E_CPU1_SA_DQ<29>";
128"M_E_CPU1_SA_DQ<17>";
129"M_E_CPU1_SA_DQ<28>";
130"M_E_CPU1_SA_DQ<16>";
131"M_E_CPU1_SA_DQ<27>";
132"M_E_CPU1_SA_DQ<26>";
133"M_E_CPU1_SA_DQ<25>";
134"M_E_CPU1_SA_DQ<24>";
135"M_E_CPU1_SA_DQ<23>";
136"M_E_CPU1_SA_DQ<22>";
137"M_E_CPU1_SA_DQ<21>";
138"M_E_CPU1_SA_DQ<20>";
139"M_E_CPU1_SA_DQ<31>";
140"M_E_CPU1_SB_DQ<1>";
141"M_E_CPU1_SA_DQ<30>";
142"M_E_CPU1_SB_DQ<0>";
143"M_E_CPU1_SA_DQ<9>";
144"M_E_CPU1_SA_DQ<8>";
145"M_E_CPU1_SA_DQ<15>";
146"M_E_CPU1_SA_DQ<7>";
147"M_E_CPU1_SA_DQ<14>";
148"M_E_CPU1_SA_DQ<6>";
149"M_E_CPU1_SA_DQ<13>";
150"M_E_CPU1_SA_DQ<5>";
151"M_E_CPU1_SA_DQ<12>";
152"M_E_CPU1_SA_DQ<4>";
153"M_E_CPU1_SA_DQ<11>";
154"M_E_CPU1_SA_DQ<3>";
155"M_E_CPU1_SA_DQ<10>";
156"M_E_CPU1_SA_DQ<2>";
157"M_E_CPU1_SA_DQ<1>";
158"M_E_CPU1_SA_DQ<0>";
%"GENOA_SP5"
"5","(-4700,3600)","0","pure_quanta","I159";
;
LOCATION"U26"
$SEC"5"
CDS_SEC"5"
PART_TYPE"SMLF"
MATERIAL"IO"
VALUE"SOCKET6096_13568-001"
CDS_LIB"pure_quanta"
CDS_LMAN_SYM_OUTLINE"-650,2525,650,-2525"
NEEDS_NO_SIZE"TRUE"
PART_NUMBER"DGA^6000030";
"TEST39E"
$PN"BF69"13;
"ME1_CLK_L"
$PN"BG71"0;
"ME1_CLK_H"
$PN"BF70"0;
"ME0_CLK_L"
$PN"BD70"15;
"ME0_CLK_H"
$PN"BC71"14;
"MEB_DQS_H9"
$PN"BV70"25;
"MEB_PAR"
$PN"BL71"23;
"MEA_PAR"
$PN"BC69"19;
"MEA_DQS_H3"
$PN"AE71"61;
"MEA_DQS_L7"
$PN"Y69"62;
"MEB_CHECK5"
$PN"BU69"79;
"MEB_DATA14"
$PN"CN71"106;
"MEB_DATA25"
$PN"DA69"88;
"MEB_DQS_L1"
$PN"CL71"42;
"MEA_DATA19"
$PN"W69"125;
"MEA_DQS_H2"
$PN"W71"63;
"MEA_DQS_L6"
$PN"P69"64;
"MEB_CHECK4"
$PN"BT70"80;
"MEB_DATA13"
$PN"CN69"107;
"MEB_DATA24"
$PN"CY70"89;
"MEB_DQS_L0"
$PN"CE71"43;
"MEA_DATA18"
$PN"V70"126;
"MEA_DATA29"
$PN"AH69"127;
"MEA_DQS_H1"
$PN"N71"65;
"MEA_DQS_L5"
$PN"H69"66;
"MEB_CHECK3"
$PN"CB69"81;
"MEB_DATA12"
$PN"CM70"108;
"MEB_DATA23"
$PN"CY69"90;
"MEA_DATA17"
$PN"V69"128;
"MEA_DATA28"
$PN"AG71"129;
"MEA_DQS_H0"
$PN"G71"67;
"MEA_DQS_L4"
$PN"AM70"68;
"MEB_CHECK2"
$PN"CA71"82;
"MEB_DATA9"
$PN"CJ69"109;
"MEB_DATA11"
$PN"CK69"110;
"MEB_DATA22"
$PN"CW71"91;
"MEA0_RSP_L"
$PN"BN69"17;
"MEA1_RSP_L"
$PN"BP69"0;
"MEA_CHECK7"
$PN"AR69"83;
"MEA_DATA9"
$PN"M69"143;
"MEA_DATA16"
$PN"U71"130;
"MEA_DATA27"
$PN"AE69"131;
"MEA_DQS_L3"
$PN"AF70"69;
"MEB_CA6"
$PN"BK70"26;
"MEB_CHECK1"
$PN"CA69"84;
"MEB_DATA8"
$PN"CH70"111;
"MEB_DATA10"
$PN"CJ71"112;
"MEB_DATA21"
$PN"CW69"92;
"MEA_CA6"
$PN"BB69"27;
"MEA_CHECK6"
$PN"AP70"93;
"MEA_DATA8"
$PN"L71"144;
"MEA_DATA15"
$PN"U69"145;
"MEA_DATA26"
$PN"AD70"132;
"MEA_DQS_L2"
$PN"Y70"70;
"MEB_CA5"
$PN"BK69"28;
"MEB_CHECK0"
$PN"BY70"85;
"MEB_DATA7"
$PN"CH69"113;
"MEB_DATA20"
$PN"CV70"114;
"MEB_DATA31"
$PN"DF69"94;
"MEA_CA5"
$PN"BB70"29;
"MEA_CHECK5"
$PN"AP69"95;
"MEA_DATA7"
$PN"L69"146;
"MEA_DATA14"
$PN"T70"147;
"MEA_DATA25"
$PN"AD69"133;
"MEA_DQS_L1"
$PN"P70"71;
"MEB0_CS_L1"
$PN"BN71"20;
"MEB1_CS_L1"
$PN"BM70"0;
"MEB_CA4"
$PN"BJ69"30;
"MEB_DATA6"
$PN"CG71"115;
"MEB_DATA30"
$PN"DE71"96;
"MEB_DQS_H8"
$PN"DD69"44;
"MEA_CA4"
$PN"BA71"31;
"MEA_CHECK4"
$PN"AN71"97;
"MEA_DATA6"
$PN"K70"148;
"MEA_DATA13"
$PN"T69"149;
"MEA_DATA24"
$PN"AC71"134;
"MEA_DQS_L0"
$PN"H70"72;
"MEB0_CS_L0"
$PN"BM69"21;
"MEB1_CS_L0"
$PN"BL69"0;
"MEB_CA3"
$PN"BJ71"32;
"MEB_DATA5"
$PN"CG69"116;
"MEB_DQS_H7"
$PN"CV69"45;
"MEA_CA3"
$PN"BA69"33;
"MEA_CHECK3"
$PN"AL69"98;
"MEA_DATA5"
$PN"K69"150;
"MEA_DATA12"
$PN"R71"151;
"MEA_DATA23"
$PN"AC69"135;
"MEB_CA2"
$PN"BH70"34;
"MEB_DATA4"
$PN"CF70"117;
"MEB_DQS_H6"
$PN"CM69"46;
"MEA_CA2"
$PN"AY69"35;
"MEA_CHECK2"
$PN"AK70"99;
"MEA_DATA4"
$PN"J71"152;
"MEA_DATA11"
$PN"N69"153;
"MEA_DATA22"
$PN"AB70"136;
"MEB_CA1"
$PN"BH69"36;
"MEB_DATA3"
$PN"CD69"118;
"MEB_DQS_H5"
$PN"CF69"47;
"MEB_DQS_L9"
$PN"BW71"37;
"MEA_CA1"
$PN"AY70"38;
"MEA_CHECK1"
$PN"AK69"100;
"MEA_DATA3"
$PN"G69"154;
"MEA_DATA10"
$PN"M70"155;
"MEA_DATA21"
$PN"AB69"137;
"MEB_CA0"
$PN"BG69"39;
"MEB_DATA2"
$PN"CC71"119;
"MEB_DQS_H4"
$PN"BY69"48;
"MEB_DQS_L8"
$PN"DC69"40;
"MEA_CA0"
$PN"AW71"41;
"MEA_CHECK0"
$PN"AJ71"101;
"MEA_DATA2"
$PN"F70"156;
"MEA_DATA20"
$PN"AA71"138;
"MEA_DATA31"
$PN"AJ69"139;
"MEA_DQS_H9"
$PN"AN69"49;
"MEB_DATA1"
$PN"CC69"140;
"MEB_DQS_H3"
$PN"DB70"50;
"MEB_DQS_L7"
$PN"CU69"51;
"MEA0_CS_L1"
$PN"AW69"18;
"MEA1_CS_L1"
$PN"AV69"0;
"MEA_DATA1"
$PN"F69"157;
"MEA_DATA30"
$PN"AH70"141;
"MEA_DQS_H8"
$PN"AG69"73;
"MEB_DATA0"
$PN"CB70"142;
"MEB_DATA19"
$PN"CT69"120;
"MEB_DQS_H2"
$PN"CT70"52;
"MEB_DQS_L6"
$PN"CL69"53;
"MEA0_CS_L0"
$PN"AV70"16;
"MEA1_CS_L0"
$PN"AU71"0;
"MEA_DATA0"
$PN"E71"158;
"MEA_DQS_H7"
$PN"AA69"74;
"MEB_DATA18"
$PN"CR71"121;
"MEB_DATA29"
$PN"DE69"102;
"MEB_DQS_H1"
$PN"CK70"54;
"MEB_DQS_L5"
$PN"CE69"55;
"MEA_DQS_H6"
$PN"R69"75;
"MEB_DATA17"
$PN"CR69"122;
"MEB_DATA28"
$PN"DD70"103;
"MEB_DQS_H0"
$PN"CD70"56;
"MEB_DQS_L4"
$PN"BW69"57;
"MEA_DQS_H5"
$PN"J69"76;
"MEA_DQS_L9"
$PN"AM69"58;
"MEB0_RSP_L"
$PN"BP70"22;
"MEB1_RSP_L"
$PN"BR71"0;
"MEB_CHECK7"
$PN"BV69"86;
"MEB_DATA16"
$PN"CP70"123;
"MEB_DATA27"
$PN"DB69"104;
"MEB_DQS_L3"
$PN"DC71"59;
"MEA_DQS_H4"
$PN"AL71"77;
"MEA_DQS_L8"
$PN"AF69"78;
"MEB_CHECK6"
$PN"BU71"87;
"MEB_DATA15"
$PN"CP69"124;
"MEB_DATA26"
$PN"DA71"105;
"MEB_DQS_L2"
$PN"CU71"60;
"ME_RESET_L"
$PN"AU69"24;
"ME_ALERT_L"
$PN"AT69"12;
%"TAP"
"1","(-3425,5975)","0","mstr_standard","I162";
;
CDS_LIB"mstr_standard"
BODY_TYPE"PLUMBING"
HDL_TAP"TRUE";
"B \NAC \NWC"1;
"S \NAC"
BN"0"158;
%"TAP"
"1","(-3425,5925)","0","mstr_standard","I163";
;
CDS_LIB"mstr_standard"
BODY_TYPE"PLUMBING"
HDL_TAP"TRUE";
"B \NAC \NWC"1;
"S \NAC"
BN"1"157;
%"TAP"
"1","(-3425,5875)","0","mstr_standard","I164";
;
CDS_LIB"mstr_standard"
BODY_TYPE"PLUMBING"
HDL_TAP"TRUE";
"B \NAC \NWC"1;
"S \NAC"
BN"2"156;
%"TAP"
"1","(-3425,5825)","0","mstr_standard","I165";
;
CDS_LIB"mstr_standard"
BODY_TYPE"PLUMBING"
HDL_TAP"TRUE";
"B \NAC \NWC"1;
"S \NAC"
BN"3"154;
%"TAP"
"1","(-3425,5775)","0","mstr_standard","I166";
;
CDS_LIB"mstr_standard"
BODY_TYPE"PLUMBING"
HDL_TAP"TRUE";
"B \NAC \NWC"1;
"S \NAC"
BN"4"152;
%"TAP"
"1","(-3425,5725)","0","mstr_standard","I167";
;
CDS_LIB"mstr_standard"
BODY_TYPE"PLUMBING"
HDL_TAP"TRUE";
"B \NAC \NWC"1;
"S \NAC"
BN"5"150;
%"TAP"
"1","(-3425,5675)","0","mstr_standard","I168";
;
CDS_LIB"mstr_standard"
BODY_TYPE"PLUMBING"
HDL_TAP"TRUE";
"B \NAC \NWC"1;
"S \NAC"
BN"6"148;
%"TAP"
"1","(-3425,5625)","0","mstr_standard","I169";
;
CDS_LIB"mstr_standard"
BODY_TYPE"PLUMBING"
HDL_TAP"TRUE";
"B \NAC \NWC"1;
"S \NAC"
BN"7"146;
%"TAP"
"1","(-3425,5525)","0","mstr_standard","I170";
;
CDS_LIB"mstr_standard"
BODY_TYPE"PLUMBING"
HDL_TAP"TRUE";
"B \NAC \NWC"1;
"S \NAC"
BN"8"144;
%"TAP"
"1","(-3425,5475)","0","mstr_standard","I171";
;
CDS_LIB"mstr_standard"
BODY_TYPE"PLUMBING"
HDL_TAP"TRUE";
"B \NAC \NWC"1;
"S \NAC"
BN"9"143;
%"TAP"
"1","(-3425,5425)","0","mstr_standard","I172";
;
CDS_LIB"mstr_standard"
BODY_TYPE"PLUMBING"
HDL_TAP"TRUE";
"B \NAC \NWC"1;
"S \NAC"
BN"10"155;
%"TAP"
"1","(-3425,5375)","0","mstr_standard","I173";
;
CDS_LIB"mstr_standard"
BODY_TYPE"PLUMBING"
HDL_TAP"TRUE";
"B \NAC \NWC"1;
"S \NAC"
BN"11"153;
%"TAP"
"1","(-3425,5325)","0","mstr_standard","I174";
;
CDS_LIB"mstr_standard"
BODY_TYPE"PLUMBING"
HDL_TAP"TRUE";
"B \NAC \NWC"1;
"S \NAC"
BN"12"151;
%"TAP"
"1","(-3425,5275)","0","mstr_standard","I175";
;
CDS_LIB"mstr_standard"
BODY_TYPE"PLUMBING"
HDL_TAP"TRUE";
"B \NAC \NWC"1;
"S \NAC"
BN"13"149;
%"TAP"
"1","(-3425,5225)","0","mstr_standard","I176";
;
CDS_LIB"mstr_standard"
BODY_TYPE"PLUMBING"
HDL_TAP"TRUE";
"B \NAC \NWC"1;
"S \NAC"
BN"14"147;
%"TAP"
"1","(-3425,5175)","0","mstr_standard","I177";
;
CDS_LIB"mstr_standard"
BODY_TYPE"PLUMBING"
HDL_TAP"TRUE";
"B \NAC \NWC"1;
"S \NAC"
BN"15"145;
%"TAP"
"1","(-3425,5075)","0","mstr_standard","I178";
;
CDS_LIB"mstr_standard"
BODY_TYPE"PLUMBING"
HDL_TAP"TRUE";
"B \NAC \NWC"1;
"S \NAC"
BN"16"130;
%"TAP"
"1","(-3425,5025)","0","mstr_standard","I179";
;
CDS_LIB"mstr_standard"
BODY_TYPE"PLUMBING"
HDL_TAP"TRUE";
"B \NAC \NWC"1;
"S \NAC"
BN"17"128;
%"TAP"
"1","(-3425,4975)","0","mstr_standard","I180";
;
CDS_LIB"mstr_standard"
BODY_TYPE"PLUMBING"
HDL_TAP"TRUE";
"B \NAC \NWC"1;
"S \NAC"
BN"18"126;
%"TAP"
"1","(-3425,4875)","0","mstr_standard","I181";
;
CDS_LIB"mstr_standard"
BODY_TYPE"PLUMBING"
HDL_TAP"TRUE";
"B \NAC \NWC"1;
"S \NAC"
BN"20"138;
%"TAP"
"1","(-3425,4925)","0","mstr_standard","I182";
;
CDS_LIB"mstr_standard"
BODY_TYPE"PLUMBING"
HDL_TAP"TRUE";
"B \NAC \NWC"1;
"S \NAC"
BN"19"125;
%"TAP"
"1","(-3425,4825)","0","mstr_standard","I183";
;
CDS_LIB"mstr_standard"
BODY_TYPE"PLUMBING"
HDL_TAP"TRUE";
"B \NAC \NWC"1;
"S \NAC"
BN"21"137;
%"TAP"
"1","(-3425,4775)","0","mstr_standard","I184";
;
CDS_LIB"mstr_standard"
BODY_TYPE"PLUMBING"
HDL_TAP"TRUE";
"B \NAC \NWC"1;
"S \NAC"
BN"22"136;
%"TAP"
"1","(-3425,4725)","0","mstr_standard","I185";
;
CDS_LIB"mstr_standard"
BODY_TYPE"PLUMBING"
HDL_TAP"TRUE";
"B \NAC \NWC"1;
"S \NAC"
BN"23"135;
%"TAP"
"1","(-3425,4625)","0","mstr_standard","I186";
;
CDS_LIB"mstr_standard"
BODY_TYPE"PLUMBING"
HDL_TAP"TRUE";
"B \NAC \NWC"1;
"S \NAC"
BN"24"134;
%"TAP"
"1","(-3425,4575)","0","mstr_standard","I187";
;
CDS_LIB"mstr_standard"
BODY_TYPE"PLUMBING"
HDL_TAP"TRUE";
"B \NAC \NWC"1;
"S \NAC"
BN"25"133;
%"TAP"
"1","(-3425,4525)","0","mstr_standard","I188";
;
CDS_LIB"mstr_standard"
BODY_TYPE"PLUMBING"
HDL_TAP"TRUE";
"B \NAC \NWC"1;
"S \NAC"
BN"26"132;
%"TAP"
"1","(-3425,4425)","0","mstr_standard","I189";
;
CDS_LIB"mstr_standard"
BODY_TYPE"PLUMBING"
HDL_TAP"TRUE";
"B \NAC \NWC"1;
"S \NAC"
BN"28"129;
%"TAP"
"1","(-3425,4475)","0","mstr_standard","I190";
;
CDS_LIB"mstr_standard"
BODY_TYPE"PLUMBING"
HDL_TAP"TRUE";
"B \NAC \NWC"1;
"S \NAC"
BN"27"131;
%"TAP"
"1","(-3425,4375)","0","mstr_standard","I191";
;
CDS_LIB"mstr_standard"
BODY_TYPE"PLUMBING"
HDL_TAP"TRUE";
"B \NAC \NWC"1;
"S \NAC"
BN"29"127;
%"TAP"
"1","(-3425,4325)","0","mstr_standard","I192";
;
CDS_LIB"mstr_standard"
BODY_TYPE"PLUMBING"
HDL_TAP"TRUE";
"B \NAC \NWC"1;
"S \NAC"
BN"30"141;
%"TAP"
"1","(-3425,4275)","0","mstr_standard","I193";
;
CDS_LIB"mstr_standard"
BODY_TYPE"PLUMBING"
HDL_TAP"TRUE";
"B \NAC \NWC"1;
"S \NAC"
BN"31"139;
%"TAP"
"1","(-3425,4175)","0","mstr_standard","I194";
;
CDS_LIB"mstr_standard"
BODY_TYPE"PLUMBING"
HDL_TAP"TRUE";
"B \NAC \NWC"2;
"S \NAC"
BN"0"142;
%"TAP"
"1","(-3425,4125)","0","mstr_standard","I195";
;
CDS_LIB"mstr_standard"
BODY_TYPE"PLUMBING"
HDL_TAP"TRUE";
"B \NAC \NWC"2;
"S \NAC"
BN"1"140;
%"TAP"
"1","(-3425,4075)","0","mstr_standard","I197";
;
CDS_LIB"mstr_standard"
BODY_TYPE"PLUMBING"
HDL_TAP"TRUE";
"B \NAC \NWC"2;
"S \NAC"
BN"2"119;
%"TAP"
"1","(-3425,3975)","0","mstr_standard","I198";
;
CDS_LIB"mstr_standard"
BODY_TYPE"PLUMBING"
HDL_TAP"TRUE";
"B \NAC \NWC"2;
"S \NAC"
BN"4"117;
%"TAP"
"1","(-3425,4025)","0","mstr_standard","I199";
;
CDS_LIB"mstr_standard"
BODY_TYPE"PLUMBING"
HDL_TAP"TRUE";
"B \NAC \NWC"2;
"S \NAC"
BN"3"118;
%"TAP"
"1","(-3425,3925)","0","mstr_standard","I200";
;
CDS_LIB"mstr_standard"
BODY_TYPE"PLUMBING"
HDL_TAP"TRUE";
"B \NAC \NWC"2;
"S \NAC"
BN"5"116;
%"TAP"
"1","(-3425,3875)","0","mstr_standard","I201";
;
CDS_LIB"mstr_standard"
BODY_TYPE"PLUMBING"
HDL_TAP"TRUE";
"B \NAC \NWC"2;
"S \NAC"
BN"6"115;
%"TAP"
"1","(-3425,3825)","0","mstr_standard","I202";
;
CDS_LIB"mstr_standard"
BODY_TYPE"PLUMBING"
HDL_TAP"TRUE";
"B \NAC \NWC"2;
"S \NAC"
BN"7"113;
%"TAP"
"1","(-3425,3725)","0","mstr_standard","I203";
;
CDS_LIB"mstr_standard"
BODY_TYPE"PLUMBING"
HDL_TAP"TRUE";
"B \NAC \NWC"2;
"S \NAC"
BN"8"111;
%"TAP"
"1","(-3425,3675)","0","mstr_standard","I204";
;
CDS_LIB"mstr_standard"
BODY_TYPE"PLUMBING"
HDL_TAP"TRUE";
"B \NAC \NWC"2;
"S \NAC"
BN"9"109;
%"TAP"
"1","(-3425,3625)","0","mstr_standard","I205";
;
CDS_LIB"mstr_standard"
BODY_TYPE"PLUMBING"
HDL_TAP"TRUE";
"B \NAC \NWC"2;
"S \NAC"
BN"10"112;
%"TAP"
"1","(-3425,3575)","0","mstr_standard","I206";
;
CDS_LIB"mstr_standard"
BODY_TYPE"PLUMBING"
HDL_TAP"TRUE";
"B \NAC \NWC"2;
"S \NAC"
BN"11"110;
%"TAP"
"1","(-3425,3525)","0","mstr_standard","I207";
;
CDS_LIB"mstr_standard"
BODY_TYPE"PLUMBING"
HDL_TAP"TRUE";
"B \NAC \NWC"2;
"S \NAC"
BN"12"108;
%"TAP"
"1","(-3425,3475)","0","mstr_standard","I208";
;
CDS_LIB"mstr_standard"
BODY_TYPE"PLUMBING"
HDL_TAP"TRUE";
"B \NAC \NWC"2;
"S \NAC"
BN"13"107;
%"TAP"
"1","(-3425,3425)","0","mstr_standard","I209";
;
CDS_LIB"mstr_standard"
BODY_TYPE"PLUMBING"
HDL_TAP"TRUE";
"B \NAC \NWC"2;
"S \NAC"
BN"14"106;
%"TAP"
"1","(-3425,3375)","0","mstr_standard","I210";
;
CDS_LIB"mstr_standard"
BODY_TYPE"PLUMBING"
HDL_TAP"TRUE";
"B \NAC \NWC"2;
"S \NAC"
BN"15"124;
%"TAP"
"1","(-3425,3275)","0","mstr_standard","I211";
;
CDS_LIB"mstr_standard"
BODY_TYPE"PLUMBING"
HDL_TAP"TRUE";
"B \NAC \NWC"2;
"S \NAC"
BN"16"123;
%"TAP"
"1","(-3425,3225)","0","mstr_standard","I212";
;
CDS_LIB"mstr_standard"
BODY_TYPE"PLUMBING"
HDL_TAP"TRUE";
"B \NAC \NWC"2;
"S \NAC"
BN"17"122;
%"TAP"
"1","(-3425,3175)","0","mstr_standard","I213";
;
CDS_LIB"mstr_standard"
BODY_TYPE"PLUMBING"
HDL_TAP"TRUE";
"B \NAC \NWC"2;
"S \NAC"
BN"18"121;
%"TAP"
"1","(-3425,3075)","0","mstr_standard","I214";
;
CDS_LIB"mstr_standard"
BODY_TYPE"PLUMBING"
HDL_TAP"TRUE";
"B \NAC \NWC"2;
"S \NAC"
BN"20"114;
%"TAP"
"1","(-3425,3125)","0","mstr_standard","I215";
;
CDS_LIB"mstr_standard"
BODY_TYPE"PLUMBING"
HDL_TAP"TRUE";
"B \NAC \NWC"2;
"S \NAC"
BN"19"120;
%"TAP"
"1","(-3425,2975)","0","mstr_standard","I216";
;
CDS_LIB"mstr_standard"
BODY_TYPE"PLUMBING"
HDL_TAP"TRUE";
"B \NAC \NWC"2;
"S \NAC"
BN"22"91;
%"TAP"
"1","(-3425,3025)","0","mstr_standard","I217";
;
CDS_LIB"mstr_standard"
BODY_TYPE"PLUMBING"
HDL_TAP"TRUE";
"B \NAC \NWC"2;
"S \NAC"
BN"21"92;
%"TAP"
"1","(-3425,2825)","0","mstr_standard","I218";
;
CDS_LIB"mstr_standard"
BODY_TYPE"PLUMBING"
HDL_TAP"TRUE";
"B \NAC \NWC"2;
"S \NAC"
BN"24"89;
%"TAP"
"1","(-3425,2925)","0","mstr_standard","I219";
;
CDS_LIB"mstr_standard"
BODY_TYPE"PLUMBING"
HDL_TAP"TRUE";
"B \NAC \NWC"2;
"S \NAC"
BN"23"90;
%"TAP"
"1","(-3425,2775)","0","mstr_standard","I220";
;
CDS_LIB"mstr_standard"
BODY_TYPE"PLUMBING"
HDL_TAP"TRUE";
"B \NAC \NWC"2;
"S \NAC"
BN"25"88;
%"TAP"
"1","(-3425,2725)","0","mstr_standard","I221";
;
CDS_LIB"mstr_standard"
BODY_TYPE"PLUMBING"
HDL_TAP"TRUE";
"B \NAC \NWC"2;
"S \NAC"
BN"26"105;
%"TAP"
"1","(-3425,2625)","0","mstr_standard","I222";
;
CDS_LIB"mstr_standard"
BODY_TYPE"PLUMBING"
HDL_TAP"TRUE";
"B \NAC \NWC"2;
"S \NAC"
BN"28"103;
%"TAP"
"1","(-3425,2675)","0","mstr_standard","I223";
;
CDS_LIB"mstr_standard"
BODY_TYPE"PLUMBING"
HDL_TAP"TRUE";
"B \NAC \NWC"2;
"S \NAC"
BN"27"104;
%"TAP"
"1","(-3425,2575)","0","mstr_standard","I224";
;
CDS_LIB"mstr_standard"
BODY_TYPE"PLUMBING"
HDL_TAP"TRUE";
"B \NAC \NWC"2;
"S \NAC"
BN"29"102;
%"TAP"
"1","(-3425,2525)","0","mstr_standard","I225";
;
CDS_LIB"mstr_standard"
BODY_TYPE"PLUMBING"
HDL_TAP"TRUE";
"B \NAC \NWC"2;
"S \NAC"
BN"30"96;
%"TAP"
"1","(-3425,2475)","0","mstr_standard","I226";
;
CDS_LIB"mstr_standard"
BODY_TYPE"PLUMBING"
HDL_TAP"TRUE";
"B \NAC \NWC"2;
"S \NAC"
BN"31"94;
%"TAP"
"1","(-3425,2375)","0","mstr_standard","I227";
;
CDS_LIB"mstr_standard"
BODY_TYPE"PLUMBING"
HDL_TAP"TRUE";
"B \NAC \NWC"3;
"S \NAC"
BN"0"101;
%"TAP"
"1","(-3425,2325)","0","mstr_standard","I228";
;
CDS_LIB"mstr_standard"
BODY_TYPE"PLUMBING"
HDL_TAP"TRUE";
"B \NAC \NWC"3;
"S \NAC"
BN"1"100;
%"TAP"
"1","(-3425,2225)","0","mstr_standard","I229";
;
CDS_LIB"mstr_standard"
BODY_TYPE"PLUMBING"
HDL_TAP"TRUE";
"B \NAC \NWC"3;
"S \NAC"
BN"3"98;
%"TAP"
"1","(-3425,2275)","0","mstr_standard","I230";
;
CDS_LIB"mstr_standard"
BODY_TYPE"PLUMBING"
HDL_TAP"TRUE";
"B \NAC \NWC"3;
"S \NAC"
BN"2"99;
%"TAP"
"1","(-3425,2125)","0","mstr_standard","I231";
;
CDS_LIB"mstr_standard"
BODY_TYPE"PLUMBING"
HDL_TAP"TRUE";
"B \NAC \NWC"3;
"S \NAC"
BN"5"95;
%"TAP"
"1","(-3425,2175)","0","mstr_standard","I232";
;
CDS_LIB"mstr_standard"
BODY_TYPE"PLUMBING"
HDL_TAP"TRUE";
"B \NAC \NWC"3;
"S \NAC"
BN"4"97;
%"TAP"
"1","(-3425,2075)","0","mstr_standard","I233";
;
CDS_LIB"mstr_standard"
BODY_TYPE"PLUMBING"
HDL_TAP"TRUE";
"B \NAC \NWC"3;
"S \NAC"
BN"6"93;
%"TAP"
"1","(-3425,2025)","0","mstr_standard","I235";
;
CDS_LIB"mstr_standard"
BODY_TYPE"PLUMBING"
HDL_TAP"TRUE";
"B \NAC \NWC"3;
"S \NAC"
BN"7"83;
%"TAP"
"1","(-3425,1925)","0","mstr_standard","I236";
;
CDS_LIB"mstr_standard"
BODY_TYPE"PLUMBING"
HDL_TAP"TRUE";
"B \NAC \NWC"4;
"S \NAC"
BN"0"85;
%"TAP"
"1","(-3425,1875)","0","mstr_standard","I237";
;
CDS_LIB"mstr_standard"
BODY_TYPE"PLUMBING"
HDL_TAP"TRUE";
"B \NAC \NWC"4;
"S \NAC"
BN"1"84;
%"TAP"
"1","(-3425,1825)","0","mstr_standard","I238";
;
CDS_LIB"mstr_standard"
BODY_TYPE"PLUMBING"
HDL_TAP"TRUE";
"B \NAC \NWC"4;
"S \NAC"
BN"2"82;
%"TAP"
"1","(-3425,1775)","0","mstr_standard","I239";
;
CDS_LIB"mstr_standard"
BODY_TYPE"PLUMBING"
HDL_TAP"TRUE";
"B \NAC \NWC"4;
"S \NAC"
BN"3"81;
%"TAP"
"1","(-3425,1675)","0","mstr_standard","I240";
;
CDS_LIB"mstr_standard"
BODY_TYPE"PLUMBING"
HDL_TAP"TRUE";
"B \NAC \NWC"4;
"S \NAC"
BN"5"79;
%"TAP"
"1","(-3425,1725)","0","mstr_standard","I241";
;
CDS_LIB"mstr_standard"
BODY_TYPE"PLUMBING"
HDL_TAP"TRUE";
"B \NAC \NWC"4;
"S \NAC"
BN"4"80;
%"TAP"
"1","(-3425,1625)","0","mstr_standard","I242";
;
CDS_LIB"mstr_standard"
BODY_TYPE"PLUMBING"
HDL_TAP"TRUE";
"B \NAC \NWC"4;
"S \NAC"
BN"6"87;
%"TAP"
"1","(-3425,1575)","0","mstr_standard","I243";
;
CDS_LIB"mstr_standard"
BODY_TYPE"PLUMBING"
HDL_TAP"TRUE";
"B \NAC \NWC"4;
"S \NAC"
BN"7"86;
%"TAP"
"1","(-5850,5975)","2","mstr_standard","I244";
;
CDS_LIB"mstr_standard"
BODY_TYPE"PLUMBING"
HDL_TAP"TRUE";
"B \NAC \NWC"6;
"S \NAC"
BN"0"67;
%"TAP"
"1","(-5850,5875)","2","mstr_standard","I245";
;
CDS_LIB"mstr_standard"
BODY_TYPE"PLUMBING"
HDL_TAP"TRUE";
"B \NAC \NWC"6;
"S \NAC"
BN"1"65;
%"TAP"
"1","(-5850,5675)","2","mstr_standard","I246";
;
CDS_LIB"mstr_standard"
BODY_TYPE"PLUMBING"
HDL_TAP"TRUE";
"B \NAC \NWC"6;
"S \NAC"
BN"3"61;
%"TAP"
"1","(-5850,5775)","2","mstr_standard","I247";
;
CDS_LIB"mstr_standard"
BODY_TYPE"PLUMBING"
HDL_TAP"TRUE";
"B \NAC \NWC"6;
"S \NAC"
BN"2"63;
%"TAP"
"1","(-6050,5925)","2","mstr_standard","I248";
;
CDS_LIB"mstr_standard"
BODY_TYPE"PLUMBING"
HDL_TAP"TRUE";
"B \NAC \NWC"5;
"S \NAC"
BN"0"72;
%"TAP"
"1","(-6050,5825)","2","mstr_standard","I249";
;
CDS_LIB"mstr_standard"
BODY_TYPE"PLUMBING"
HDL_TAP"TRUE";
"B \NAC \NWC"5;
"S \NAC"
BN"1"71;
%"TAP"
"1","(-6050,5725)","2","mstr_standard","I250";
;
CDS_LIB"mstr_standard"
BODY_TYPE"PLUMBING"
HDL_TAP"TRUE";
"B \NAC \NWC"5;
"S \NAC"
BN"2"70;
%"TAP"
"1","(-5850,5475)","2","mstr_standard","I251";
;
CDS_LIB"mstr_standard"
BODY_TYPE"PLUMBING"
HDL_TAP"TRUE";
"B \NAC \NWC"6;
"S \NAC"
BN"5"76;
%"TAP"
"1","(-5850,5575)","2","mstr_standard","I252";
;
CDS_LIB"mstr_standard"
BODY_TYPE"PLUMBING"
HDL_TAP"TRUE";
"B \NAC \NWC"6;
"S \NAC"
BN"4"77;
%"TAP"
"1","(-5850,5375)","2","mstr_standard","I253";
;
CDS_LIB"mstr_standard"
BODY_TYPE"PLUMBING"
HDL_TAP"TRUE";
"B \NAC \NWC"6;
"S \NAC"
BN"6"75;
%"TAP"
"1","(-5850,5175)","2","mstr_standard","I254";
;
CDS_LIB"mstr_standard"
BODY_TYPE"PLUMBING"
HDL_TAP"TRUE";
"B \NAC \NWC"6;
"S \NAC"
BN"8"73;
%"TAP"
"1","(-5850,5275)","2","mstr_standard","I255";
;
CDS_LIB"mstr_standard"
BODY_TYPE"PLUMBING"
HDL_TAP"TRUE";
"B \NAC \NWC"6;
"S \NAC"
BN"7"74;
%"TAP"
"1","(-6050,5625)","2","mstr_standard","I256";
;
CDS_LIB"mstr_standard"
BODY_TYPE"PLUMBING"
HDL_TAP"TRUE";
"B \NAC \NWC"5;
"S \NAC"
BN"3"69;
%"TAP"
"1","(-6050,5525)","2","mstr_standard","I257";
;
CDS_LIB"mstr_standard"
BODY_TYPE"PLUMBING"
HDL_TAP"TRUE";
"B \NAC \NWC"5;
"S \NAC"
BN"4"68;
%"TAP"
"1","(-6050,5425)","2","mstr_standard","I258";
;
CDS_LIB"mstr_standard"
BODY_TYPE"PLUMBING"
HDL_TAP"TRUE";
"B \NAC \NWC"5;
"S \NAC"
BN"5"66;
%"TAP"
"1","(-6050,5325)","2","mstr_standard","I259";
;
CDS_LIB"mstr_standard"
BODY_TYPE"PLUMBING"
HDL_TAP"TRUE";
"B \NAC \NWC"5;
"S \NAC"
BN"6"64;
%"TAP"
"1","(-6050,5125)","2","mstr_standard","I260";
;
CDS_LIB"mstr_standard"
BODY_TYPE"PLUMBING"
HDL_TAP"TRUE";
"B \NAC \NWC"5;
"S \NAC"
BN"8"78;
%"TAP"
"1","(-6050,5225)","2","mstr_standard","I261";
;
CDS_LIB"mstr_standard"
BODY_TYPE"PLUMBING"
HDL_TAP"TRUE";
"B \NAC \NWC"5;
"S \NAC"
BN"7"62;
%"TAP"
"1","(-5850,4925)","2","mstr_standard","I262";
;
CDS_LIB"mstr_standard"
BODY_TYPE"PLUMBING"
HDL_TAP"TRUE";
"B \NAC \NWC"8;
"S \NAC"
BN"0"56;
%"TAP"
"1","(-5850,5075)","2","mstr_standard","I263";
;
CDS_LIB"mstr_standard"
BODY_TYPE"PLUMBING"
HDL_TAP"TRUE";
"B \NAC \NWC"6;
"S \NAC"
BN"9"49;
%"TAP"
"1","(-5850,4825)","2","mstr_standard","I264";
;
CDS_LIB"mstr_standard"
BODY_TYPE"PLUMBING"
HDL_TAP"TRUE";
"B \NAC \NWC"8;
"S \NAC"
BN"1"54;
%"TAP"
"1","(-5850,4725)","2","mstr_standard","I265";
;
CDS_LIB"mstr_standard"
BODY_TYPE"PLUMBING"
HDL_TAP"TRUE";
"B \NAC \NWC"8;
"S \NAC"
BN"2"52;
%"TAP"
"1","(-5850,4625)","2","mstr_standard","I266";
;
CDS_LIB"mstr_standard"
BODY_TYPE"PLUMBING"
HDL_TAP"TRUE";
"B \NAC \NWC"8;
"S \NAC"
BN"3"50;
%"TAP"
"1","(-6050,5025)","2","mstr_standard","I267";
;
CDS_LIB"mstr_standard"
BODY_TYPE"PLUMBING"
HDL_TAP"TRUE";
"B \NAC \NWC"5;
"S \NAC"
BN"9"58;
%"TAP"
"1","(-6050,4875)","2","mstr_standard","I268";
;
CDS_LIB"mstr_standard"
BODY_TYPE"PLUMBING"
HDL_TAP"TRUE";
"B \NAC \NWC"7;
"S \NAC"
BN"0"43;
%"TAP"
"1","(-6050,4775)","2","mstr_standard","I269";
;
CDS_LIB"mstr_standard"
BODY_TYPE"PLUMBING"
HDL_TAP"TRUE";
"B \NAC \NWC"7;
"S \NAC"
BN"1"42;
%"TAP"
"1","(-6050,4675)","2","mstr_standard","I270";
;
CDS_LIB"mstr_standard"
BODY_TYPE"PLUMBING"
HDL_TAP"TRUE";
"B \NAC \NWC"7;
"S \NAC"
BN"2"60;
%"TAP"
"1","(-5850,4425)","2","mstr_standard","I271";
;
CDS_LIB"mstr_standard"
BODY_TYPE"PLUMBING"
HDL_TAP"TRUE";
"B \NAC \NWC"8;
"S \NAC"
BN"5"47;
%"TAP"
"1","(-5850,4525)","2","mstr_standard","I272";
;
CDS_LIB"mstr_standard"
BODY_TYPE"PLUMBING"
HDL_TAP"TRUE";
"B \NAC \NWC"8;
"S \NAC"
BN"4"48;
%"TAP"
"1","(-5850,4325)","2","mstr_standard","I273";
;
CDS_LIB"mstr_standard"
BODY_TYPE"PLUMBING"
HDL_TAP"TRUE";
"B \NAC \NWC"8;
"S \NAC"
BN"6"46;
%"TAP"
"1","(-5850,4125)","2","mstr_standard","I274";
;
CDS_LIB"mstr_standard"
BODY_TYPE"PLUMBING"
HDL_TAP"TRUE";
"B \NAC \NWC"8;
"S \NAC"
BN"8"44;
%"TAP"
"1","(-5850,4225)","2","mstr_standard","I275";
;
CDS_LIB"mstr_standard"
BODY_TYPE"PLUMBING"
HDL_TAP"TRUE";
"B \NAC \NWC"8;
"S \NAC"
BN"7"45;
%"TAP"
"1","(-6050,4575)","2","mstr_standard","I276";
;
CDS_LIB"mstr_standard"
BODY_TYPE"PLUMBING"
HDL_TAP"TRUE";
"B \NAC \NWC"7;
"S \NAC"
BN"3"59;
%"TAP"
"1","(-6050,4475)","2","mstr_standard","I277";
;
CDS_LIB"mstr_standard"
BODY_TYPE"PLUMBING"
HDL_TAP"TRUE";
"B \NAC \NWC"7;
"S \NAC"
BN"4"57;
%"TAP"
"1","(-6050,4375)","2","mstr_standard","I278";
;
CDS_LIB"mstr_standard"
BODY_TYPE"PLUMBING"
HDL_TAP"TRUE";
"B \NAC \NWC"7;
"S \NAC"
BN"5"55;
%"TAP"
"1","(-6050,4275)","2","mstr_standard","I279";
;
CDS_LIB"mstr_standard"
BODY_TYPE"PLUMBING"
HDL_TAP"TRUE";
"B \NAC \NWC"7;
"S \NAC"
BN"6"53;
%"TAP"
"1","(-6050,4175)","2","mstr_standard","I280";
;
CDS_LIB"mstr_standard"
BODY_TYPE"PLUMBING"
HDL_TAP"TRUE";
"B \NAC \NWC"7;
"S \NAC"
BN"7"51;
%"TAP"
"1","(-5850,4025)","2","mstr_standard","I285";
;
CDS_LIB"mstr_standard"
BODY_TYPE"PLUMBING"
HDL_TAP"TRUE";
"B \NAC \NWC"8;
"S \NAC"
BN"9"25;
%"TAP"
"1","(-6050,4075)","2","mstr_standard","I286";
;
CDS_LIB"mstr_standard"
BODY_TYPE"PLUMBING"
HDL_TAP"TRUE";
"B \NAC \NWC"7;
"S \NAC"
BN"8"40;
%"TAP"
"1","(-6050,3975)","2","mstr_standard","I287";
;
CDS_LIB"mstr_standard"
BODY_TYPE"PLUMBING"
HDL_TAP"TRUE";
"B \NAC \NWC"7;
"S \NAC"
BN"9"37;
%"TAP"
"1","(-6050,3825)","2","mstr_standard","I288";
;
CDS_LIB"mstr_standard"
BODY_TYPE"PLUMBING"
HDL_TAP"TRUE";
"B \NAC \NWC"9;
"S \NAC"
BN"0"41;
%"TAP"
"1","(-6050,3775)","2","mstr_standard","I289";
;
CDS_LIB"mstr_standard"
BODY_TYPE"PLUMBING"
HDL_TAP"TRUE";
"B \NAC \NWC"9;
"S \NAC"
BN"1"38;
%"TAP"
"1","(-6050,3725)","2","mstr_standard","I290";
;
CDS_LIB"mstr_standard"
BODY_TYPE"PLUMBING"
HDL_TAP"TRUE";
"B \NAC \NWC"9;
"S \NAC"
BN"2"35;
%"TAP"
"1","(-6050,3675)","2","mstr_standard","I291";
;
CDS_LIB"mstr_standard"
BODY_TYPE"PLUMBING"
HDL_TAP"TRUE";
"B \NAC \NWC"9;
"S \NAC"
BN"3"33;
%"TAP"
"1","(-6050,3625)","2","mstr_standard","I292";
;
CDS_LIB"mstr_standard"
BODY_TYPE"PLUMBING"
HDL_TAP"TRUE";
"B \NAC \NWC"9;
"S \NAC"
BN"4"31;
%"TAP"
"1","(-6050,3575)","2","mstr_standard","I293";
;
CDS_LIB"mstr_standard"
BODY_TYPE"PLUMBING"
HDL_TAP"TRUE";
"B \NAC \NWC"9;
"S \NAC"
BN"5"29;
%"TAP"
"1","(-6050,3525)","2","mstr_standard","I294";
;
CDS_LIB"mstr_standard"
BODY_TYPE"PLUMBING"
HDL_TAP"TRUE";
"B \NAC \NWC"9;
"S \NAC"
BN"6"27;
%"TAP"
"1","(-6050,3425)","2","mstr_standard","I295";
;
CDS_LIB"mstr_standard"
BODY_TYPE"PLUMBING"
HDL_TAP"TRUE";
"B \NAC \NWC"10;
"S \NAC"
BN"0"39;
%"TAP"
"1","(-6050,3375)","2","mstr_standard","I296";
;
CDS_LIB"mstr_standard"
BODY_TYPE"PLUMBING"
HDL_TAP"TRUE";
"B \NAC \NWC"10;
"S \NAC"
BN"1"36;
%"TAP"
"1","(-6050,3325)","2","mstr_standard","I297";
;
CDS_LIB"mstr_standard"
BODY_TYPE"PLUMBING"
HDL_TAP"TRUE";
"B \NAC \NWC"10;
"S \NAC"
BN"2"34;
%"TAP"
"1","(-6050,3275)","2","mstr_standard","I298";
;
CDS_LIB"mstr_standard"
BODY_TYPE"PLUMBING"
HDL_TAP"TRUE";
"B \NAC \NWC"10;
"S \NAC"
BN"3"32;
%"TAP"
"1","(-6050,3225)","2","mstr_standard","I299";
;
CDS_LIB"mstr_standard"
BODY_TYPE"PLUMBING"
HDL_TAP"TRUE";
"B \NAC \NWC"10;
"S \NAC"
BN"4"30;
%"TAP"
"1","(-6050,3125)","2","mstr_standard","I300";
;
CDS_LIB"mstr_standard"
BODY_TYPE"PLUMBING"
HDL_TAP"TRUE";
"B \NAC \NWC"10;
"S \NAC"
BN"6"26;
%"TAP"
"1","(-6050,3175)","2","mstr_standard","I301";
;
CDS_LIB"mstr_standard"
BODY_TYPE"PLUMBING"
HDL_TAP"TRUE";
"B \NAC \NWC"10;
"S \NAC"
BN"5"28;
%"Q_RES"
"1","(-6725,2125)","0","pure_quanta","I314";
;
LOCATION"R504"
$SEC"1"
CDS_SEC"1"
PACK_TYPE"0402LF"
TOLERANCE"1%"
VALUE"15"
MATERIAL"CHIP"
WATTAGE"1/16W"
CDS_LIB"pure_quanta"
PART_NUMBER"CS01502FB03";
"B"
$PN"2"12;
"A"
$PN"1"11;
END.
